(kicad_pcb
	(version 20260206)
	(generator "pcbnew")
	(generator_version "10.0")
	(general
		(thickness 1.6)
		(legacy_teardrops no)
	)
	(paper "A4")
	(title_block
		(title "9054_F0T_PDB_BD_GPU_F_V04_1213_1550_OCP.brd")
		(comment 1 "Grand Teton / footprints 93-99 of 608")
	)
	(layers
		(0 "F.Cu" signal "TOP")
		(4 "In1.Cu" signal "GND")
		(6 "In2.Cu" signal "IN1")
		(8 "In3.Cu" signal "GND1")
		(10 "In4.Cu" signal "VCC")
		(12 "In5.Cu" signal "VCC1")
		(14 "In6.Cu" signal "GND2")
		(16 "In7.Cu" signal "IN2")
		(18 "In8.Cu" signal "GND3")
		(2 "B.Cu" signal "BOTTOM")
		(9 "F.Adhes" user "F.Adhesive")
		(11 "B.Adhes" user "B.Adhesive")
		(13 "F.Paste" user "Package Geometry/Pastemask Top")
		(15 "B.Paste" user "Package Geometry/Pastemask Bottom")
		(5 "F.SilkS" user "Ref Des/Silkscreen Top")
		(7 "B.SilkS" user "Ref Des/Silkscreen Bottom")
		(1 "F.Mask" user "Board Geometry/Soldermask Top")
		(3 "B.Mask" user "Board Geometry/Soldermask Bottom")
		(17 "Dwgs.User" user "User.Drawings")
		(19 "Cmts.User" user "User.Comments")
		(21 "Eco1.User" user "User.Eco1")
		(23 "Eco2.User" user "User.Eco2")
		(25 "Edge.Cuts" user "Board Geometry/Outline")
		(27 "Margin" user)
		(31 "F.CrtYd" user "Package Geometry/Place Bound Top")
		(29 "B.CrtYd" user "Package Geometry/Place Bound Bottom")
		(35 "F.Fab" user "Ref Des/Assembly Top")
		(33 "B.Fab" user "Ref Des/Assembly Bottom")
	)
	(footprint ""
		(layer "F.Cu")
		(at 412.0134 -38.227 -90)
		(property "Reference" "R424"
			(at 0 0 270)
			(layer "F.SilkS")
			(hide yes)
			(effects
				(font
					(size 1.27 1.27)
				)
			)
		)
		(property "Value" ""
			(at 0 0 270)
			(layer "F.Fab")
			(effects
				(font
					(size 1.27 1.27)
				)
			)
		)
		(duplicate_pad_numbers_are_jumpers no)
		(fp_line
			(start -0.7874 0.4064)
			(end -0.7874 -0.4064)
			(stroke
				(width 0.1524)
				(type default)
			)
			(layer "F.SilkS")
		)
		(fp_line
			(start 0.7874 0.4064)
			(end -0.7874 0.4064)
			(stroke
				(width 0.1524)
				(type default)
			)
			(layer "F.SilkS")
		)
		(fp_line
			(start -0.7874 -0.4064)
			(end 0.7874 -0.4064)
			(stroke
				(width 0.1524)
				(type default)
			)
			(layer "F.SilkS")
		)
		(fp_line
			(start 0.7874 -0.4064)
			(end 0.7874 0.4064)
			(stroke
				(width 0.1524)
				(type default)
			)
			(layer "F.SilkS")
		)
		(fp_line
			(start -0.67945 0.3048)
			(end -0.67945 -0.305054)
			(stroke
				(width 0.1)
				(type default)
			)
			(layer "F.Fab")
		)
		(fp_line
			(start -0.12065 0.3048)
			(end -0.67945 0.3048)
			(stroke
				(width 0.1)
				(type default)
			)
			(layer "F.Fab")
		)
		(fp_line
			(start 0.120396 0.3048)
			(end 0.120396 0.2794)
			(stroke
				(width 0.1)
				(type default)
			)
			(layer "F.Fab")
		)
		(fp_line
			(start 0.67945 0.3048)
			(end 0.120396 0.3048)
			(stroke
				(width 0.1)
				(type default)
			)
			(layer "F.Fab")
		)
		(fp_line
			(start -0.12065 0.2794)
			(end -0.12065 0.3048)
			(stroke
				(width 0.1)
				(type default)
			)
			(layer "F.Fab")
		)
		(fp_line
			(start 0.120396 0.2794)
			(end -0.12065 0.2794)
			(stroke
				(width 0.1)
				(type default)
			)
			(layer "F.Fab")
		)
		(fp_line
			(start -0.12065 -0.2794)
			(end 0.12065 -0.2794)
			(stroke
				(width 0.1)
				(type default)
			)
			(layer "F.Fab")
		)
		(fp_line
			(start 0.12065 -0.2794)
			(end 0.12065 -0.3048)
			(stroke
				(width 0.1)
				(type default)
			)
			(layer "F.Fab")
		)
		(fp_line
			(start 0.12065 -0.3048)
			(end 0.67945 -0.3048)
			(stroke
				(width 0.1)
				(type default)
			)
			(layer "F.Fab")
		)
		(fp_line
			(start 0.67945 -0.3048)
			(end 0.67945 0.3048)
			(stroke
				(width 0.1)
				(type default)
			)
			(layer "F.Fab")
		)
		(fp_line
			(start -0.67945 -0.305054)
			(end -0.12065 -0.305054)
			(stroke
				(width 0.1)
				(type default)
			)
			(layer "F.Fab")
		)
		(fp_line
			(start -0.12065 -0.305054)
			(end -0.12065 -0.2794)
			(stroke
				(width 0.1)
				(type default)
			)
			(layer "F.Fab")
		)
		(pad "1" smd circle
			(at -0.40005 0 270)
			(size 0 0)
			(layers "F.Cu" "F.Mask" "F.Paste")
			(net "PWRGD_P52V_HS2_4287_PG_N")
		)
		(pad "2" smd circle
			(at 0.40005 0 270)
			(size 0 0)
			(layers "F.Cu" "F.Mask" "F.Paste")
			(net "PWRGD_P52V_HS2_4287_PG_R_N")
		)
	)
	(footprint ""
		(layer "F.Cu")
		(at 449.3514 -92.202)
		(property "Reference" "PC59"
			(at 0 0 0)
			(layer "F.SilkS")
			(hide yes)
			(effects
				(font
					(size 1.27 1.27)
				)
			)
		)
		(property "Value" ""
			(at 0 0 0)
			(layer "F.Fab")
			(effects
				(font
					(size 1.27 1.27)
				)
			)
		)
		(duplicate_pad_numbers_are_jumpers no)
		(fp_line
			(start -1.524 -0.762)
			(end 1.524 -0.762)
			(stroke
				(width 0.1524)
				(type default)
			)
			(layer "F.SilkS")
		)
		(fp_line
			(start -1.524 0.762)
			(end -1.524 -0.762)
			(stroke
				(width 0.1524)
				(type default)
			)
			(layer "F.SilkS")
		)
		(fp_line
			(start 1.524 -0.762)
			(end 1.524 0.762)
			(stroke
				(width 0.1524)
				(type default)
			)
			(layer "F.SilkS")
		)
		(fp_line
			(start 1.524 0.762)
			(end -1.524 0.762)
			(stroke
				(width 0.1524)
				(type default)
			)
			(layer "F.SilkS")
		)
		(fp_line
			(start -1.1049 -0.724916)
			(end -1.1049 0.724916)
			(stroke
				(width 0.1)
				(type default)
			)
			(layer "F.Fab")
		)
		(fp_line
			(start -1.1049 0.724916)
			(end 1.1049 0.724916)
			(stroke
				(width 0.1)
				(type default)
			)
			(layer "F.Fab")
		)
		(fp_line
			(start 1.1049 -0.724916)
			(end -1.1049 -0.724916)
			(stroke
				(width 0.1)
				(type default)
			)
			(layer "F.Fab")
		)
		(fp_line
			(start 1.1049 0.724916)
			(end 1.1049 -0.724916)
			(stroke
				(width 0.1)
				(type default)
			)
			(layer "F.Fab")
		)
		(pad "1" smd rect
			(at -0.889 0 180)
			(size 1.016 1.27)
			(layers "F.Cu" "F.Mask" "F.Paste")
			(net "SW_P3V3_HPDB_FLT")
		)
		(pad "2" smd rect
			(at 0.889 0 180)
			(size 1.016 1.27)
			(layers "F.Cu" "F.Mask" "F.Paste")
			(net "GND")
		)
	)
	(footprint ""
		(layer "F.Cu")
		(at 409.956 -42.037)
		(property "Reference" "R5912"
			(at 0 0 0)
			(layer "F.SilkS")
			(hide yes)
			(effects
				(font
					(size 1.27 1.27)
				)
			)
		)
		(property "Value" ""
			(at 0 0 0)
			(layer "F.Fab")
			(effects
				(font
					(size 1.27 1.27)
				)
			)
		)
		(duplicate_pad_numbers_are_jumpers no)
		(fp_line
			(start -0.7874 -0.4064)
			(end 0.7874 -0.4064)
			(stroke
				(width 0.1524)
				(type default)
			)
			(layer "F.SilkS")
		)
		(fp_line
			(start -0.7874 0.4064)
			(end -0.7874 -0.4064)
			(stroke
				(width 0.1524)
				(type default)
			)
			(layer "F.SilkS")
		)
		(fp_line
			(start 0.7874 -0.4064)
			(end 0.7874 0.4064)
			(stroke
				(width 0.1524)
				(type default)
			)
			(layer "F.SilkS")
		)
		(fp_line
			(start 0.7874 0.4064)
			(end -0.7874 0.4064)
			(stroke
				(width 0.1524)
				(type default)
			)
			(layer "F.SilkS")
		)
		(fp_line
			(start -0.67945 -0.305054)
			(end -0.12065 -0.305054)
			(stroke
				(width 0.1)
				(type default)
			)
			(layer "F.Fab")
		)
		(fp_line
			(start -0.67945 0.3048)
			(end -0.67945 -0.305054)
			(stroke
				(width 0.1)
				(type default)
			)
			(layer "F.Fab")
		)
		(fp_line
			(start -0.12065 -0.305054)
			(end -0.12065 -0.2794)
			(stroke
				(width 0.1)
				(type default)
			)
			(layer "F.Fab")
		)
		(fp_line
			(start -0.12065 -0.2794)
			(end 0.12065 -0.2794)
			(stroke
				(width 0.1)
				(type default)
			)
			(layer "F.Fab")
		)
		(fp_line
			(start -0.12065 0.2794)
			(end -0.12065 0.3048)
			(stroke
				(width 0.1)
				(type default)
			)
			(layer "F.Fab")
		)
		(fp_line
			(start -0.12065 0.3048)
			(end -0.67945 0.3048)
			(stroke
				(width 0.1)
				(type default)
			)
			(layer "F.Fab")
		)
		(fp_line
			(start 0.120396 0.2794)
			(end -0.12065 0.2794)
			(stroke
				(width 0.1)
				(type default)
			)
			(layer "F.Fab")
		)
		(fp_line
			(start 0.120396 0.3048)
			(end 0.120396 0.2794)
			(stroke
				(width 0.1)
				(type default)
			)
			(layer "F.Fab")
		)
		(fp_line
			(start 0.12065 -0.3048)
			(end 0.67945 -0.3048)
			(stroke
				(width 0.1)
				(type default)
			)
			(layer "F.Fab")
		)
		(fp_line
			(start 0.12065 -0.2794)
			(end 0.12065 -0.3048)
			(stroke
				(width 0.1)
				(type default)
			)
			(layer "F.Fab")
		)
		(fp_line
			(start 0.67945 -0.3048)
			(end 0.67945 0.3048)
			(stroke
				(width 0.1)
				(type default)
			)
			(layer "F.Fab")
		)
		(fp_line
			(start 0.67945 0.3048)
			(end 0.120396 0.3048)
			(stroke
				(width 0.1)
				(type default)
			)
			(layer "F.Fab")
		)
		(pad "1" smd circle
			(at -0.40005 0)
			(size 0 0)
			(layers "F.Cu" "F.Mask" "F.Paste")
			(net "P3V3_AUX")
		)
		(pad "2" smd circle
			(at 0.40005 0)
			(size 0 0)
			(layers "F.Cu" "F.Mask" "F.Paste")
			(net "PRSNT_FAN_BP1_R_N")
		)
	)
	(footprint ""
		(layer "F.Cu")
		(at 469.539828 -122.350022 90)
		(property "Reference" "J15"
			(at -6.425692 -0.884428 0)
			(unlocked yes)
			(layer "F.SilkS")
			(effects
				(font
					(size 0.7874 0.5842)
					(thickness 0.1524)
				)
				(justify left)
			)
		)
		(property "Value" ""
			(at 0 0 90)
			(layer "F.Fab")
			(effects
				(font
					(size 1.27 1.27)
				)
			)
		)
		(duplicate_pad_numbers_are_jumpers no)
		(fp_circle
			(center 0 0)
			(end 0 5.3848)
			(stroke
				(width 0.1524)
				(type default)
			)
			(fill no)
			(layer "F.SilkS")
		)
		(fp_line
			(start 3.999992 -2.999994)
			(end 4.000246 2.999994)
			(stroke
				(width 0.1)
				(type default)
			)
			(layer "F.Fab")
		)
		(fp_line
			(start -3.999992 2.999994)
			(end -3.999738 -2.999994)
			(stroke
				(width 0.1)
				(type default)
			)
			(layer "F.Fab")
		)
		(fp_arc
			(start -3.999738 -2.999994)
			(mid 0.000178 -4.99999)
			(end 3.999992 -2.999994)
			(stroke
				(width 0.1)
				(type default)
			)
			(layer "F.Fab")
		)
		(fp_arc
			(start 4.000246 2.999994)
			(mid 0.000178 4.99999)
			(end -3.999992 2.999994)
			(stroke
				(width 0.1)
				(type default)
			)
			(layer "F.Fab")
		)
		(pad "G1" thru_hole oval
			(at 0 -3.262376 90)
			(size 1.8796 3.1242)
			(drill oval 1.6256 2.8702)
			(layers "*.Cu" "*.Mask")
			(remove_unused_layers no)
			(net "GND")
			(clearance 0.254)
			(thermal_gap 0.254)
		)
		(pad "SCR_G1" thru_hole circle
			(at 0 0 90)
			(size 10.5156 10.5156)
			(drill 5.1562)
			(layers "*.Cu" "*.Mask")
			(remove_unused_layers no)
			(net "GND")
			(clearance 0)
		)
		(zone
			(layers "F.Cu" "B.Cu" "In1.Cu" "In2.Cu" "In3.Cu" "In4.Cu" "In5.Cu" "In6.Cu"
				"In7.Cu" "In8.Cu"
			)
			(hatch none 0.5)
			(connect_pads
				(clearance 0)
			)
			(min_thickness 0.25)
			(keepout
				(tracks not_allowed)
				(vias allowed)
				(pads allowed)
				(copperpour not_allowed)
				(footprints allowed)
			)
			(placement
				(enabled no)
				(sheetname "")
			)
			(fill
				(thermal_gap 0.5)
				(thermal_bridge_width 0.5)
				(island_removal_mode 0)
			)
			(polygon
				(pts
					(arc
						(start 542.615628 -124.001022)
						(mid 532.100028 -124.001022)
						(end 542.615628 -124.001022)
					)
				)
			)
		)
	)
	(footprint ""
		(layer "F.Cu")
		(at 306.7304 -37.9222)
		(property "Reference" "PR6954"
			(at 0 0 0)
			(layer "F.SilkS")
			(hide yes)
			(effects
				(font
					(size 1.27 1.27)
				)
			)
		)
		(property "Value" ""
			(at 0 0 0)
			(layer "F.Fab")
			(effects
				(font
					(size 1.27 1.27)
				)
			)
		)
		(duplicate_pad_numbers_are_jumpers no)
		(fp_line
			(start -1.2954 -0.5842)
			(end 1.2954 -0.5842)
			(stroke
				(width 0.1524)
				(type default)
			)
			(layer "F.SilkS")
		)
		(fp_line
			(start -1.2954 0.5842)
			(end -1.2954 -0.5842)
			(stroke
				(width 0.1524)
				(type default)
			)
			(layer "F.SilkS")
		)
		(fp_line
			(start 1.2954 -0.5842)
			(end 1.2954 0.5842)
			(stroke
				(width 0.1524)
				(type default)
			)
			(layer "F.SilkS")
		)
		(fp_line
			(start 1.2954 0.5842)
			(end -1.2954 0.5842)
			(stroke
				(width 0.1524)
				(type default)
			)
			(layer "F.SilkS")
		)
		(fp_line
			(start -1.1938 -0.406654)
			(end -0.8636 -0.406654)
			(stroke
				(width 0.1)
				(type default)
			)
			(layer "F.Fab")
		)
		(fp_line
			(start -1.1938 0.4064)
			(end -1.1938 -0.406654)
			(stroke
				(width 0.1)
				(type default)
			)
			(layer "F.Fab")
		)
		(fp_line
			(start -0.8636 -0.4572)
			(end 0.8636 -0.4572)
			(stroke
				(width 0.1)
				(type default)
			)
			(layer "F.Fab")
		)
		(fp_line
			(start -0.8636 -0.406654)
			(end -0.8636 -0.4572)
			(stroke
				(width 0.1)
				(type default)
			)
			(layer "F.Fab")
		)
		(fp_line
			(start -0.8636 0.4064)
			(end -1.1938 0.4064)
			(stroke
				(width 0.1)
				(type default)
			)
			(layer "F.Fab")
		)
		(fp_line
			(start -0.8636 0.4318)
			(end -0.8636 0.4064)
			(stroke
				(width 0.1)
				(type default)
			)
			(layer "F.Fab")
		)
		(fp_line
			(start -0.8636 0.4572)
			(end -0.8636 0.4318)
			(stroke
				(width 0.1)
				(type default)
			)
			(layer "F.Fab")
		)
		(fp_line
			(start 0.8636 -0.4572)
			(end 0.8636 -0.406654)
			(stroke
				(width 0.1)
				(type default)
			)
			(layer "F.Fab")
		)
		(fp_line
			(start 0.8636 -0.406654)
			(end 1.1938 -0.406654)
			(stroke
				(width 0.1)
				(type default)
			)
			(layer "F.Fab")
		)
		(fp_line
			(start 0.8636 0.4064)
			(end 0.8636 0.4572)
			(stroke
				(width 0.1)
				(type default)
			)
			(layer "F.Fab")
		)
		(fp_line
			(start 0.8636 0.4572)
			(end -0.8636 0.4572)
			(stroke
				(width 0.1)
				(type default)
			)
			(layer "F.Fab")
		)
		(fp_line
			(start 1.1938 -0.406654)
			(end 1.1938 0.4064)
			(stroke
				(width 0.1)
				(type default)
			)
			(layer "F.Fab")
		)
		(fp_line
			(start 1.1938 0.4064)
			(end 0.8636 0.4064)
			(stroke
				(width 0.1)
				(type default)
			)
			(layer "F.Fab")
		)
		(pad "1" smd rect
			(at -0.7366 0 270)
			(size 0.7112 0.8128)
			(layers "F.Cu" "F.Mask" "F.Paste")
			(net "P52V_HS_4287_S2N")
		)
		(pad "2" smd rect
			(at 0.7366 0 270)
			(size 0.7112 0.8128)
			(layers "F.Cu" "F.Mask" "F.Paste")
			(net "P52V_HS1_SENSE_N_R2")
		)
	)
	(footprint ""
		(layer "F.Cu")
		(at 323.13626 -40.8178 180)
		(property "Reference" "PQ6"
			(at -9.628886 -3.917188 0)
			(unlocked yes)
			(layer "F.SilkS")
			(effects
				(font
					(size 0.7874 0.5842)
					(thickness 0.1524)
				)
				(justify left)
			)
		)
		(property "Value" ""
			(at 0 0 180)
			(layer "F.Fab")
			(effects
				(font
					(size 1.27 1.27)
				)
			)
		)
		(duplicate_pad_numbers_are_jumpers no)
		(fp_line
			(start 7.649972 4.99999)
			(end 7.649972 -4.99999)
			(stroke
				(width 0.1524)
				(type default)
			)
			(layer "F.SilkS")
		)
		(fp_line
			(start 7.649972 -4.99999)
			(end 7.630414 -4.99999)
			(stroke
				(width 0.1524)
				(type default)
			)
			(layer "F.SilkS")
		)
		(fp_line
			(start 7.630414 4.99999)
			(end 7.649972 4.99999)
			(stroke
				(width 0.1524)
				(type default)
			)
			(layer "F.SilkS")
		)
		(fp_line
			(start 5.115814 -4.99999)
			(end -7.649972 -4.99999)
			(stroke
				(width 0.1524)
				(type default)
			)
			(layer "F.SilkS")
		)
		(fp_line
			(start -7.649972 4.99999)
			(end 5.115814 4.99999)
			(stroke
				(width 0.1524)
				(type default)
			)
			(layer "F.SilkS")
		)
		(fp_line
			(start -7.649972 3.3274)
			(end -7.649972 4.99999)
			(stroke
				(width 0.1524)
				(type default)
			)
			(layer "F.SilkS")
		)
		(fp_line
			(start -7.649972 -1.7526)
			(end -7.649972 1.7526)
			(stroke
				(width 0.1524)
				(type default)
			)
			(layer "F.SilkS")
		)
		(fp_line
			(start -7.649972 -4.99999)
			(end -7.649972 -3.3274)
			(stroke
				(width 0.1524)
				(type default)
			)
			(layer "F.SilkS")
		)
		(fp_line
			(start 7.649972 4.99999)
			(end 7.649972 -4.99999)
			(stroke
				(width 0.1)
				(type default)
			)
			(layer "F.Fab")
		)
		(fp_line
			(start 7.649972 -4.99999)
			(end -7.649972 -4.99999)
			(stroke
				(width 0.1)
				(type default)
			)
			(layer "F.Fab")
		)
		(fp_line
			(start -7.649972 4.99999)
			(end 7.649972 4.99999)
			(stroke
				(width 0.1)
				(type default)
			)
			(layer "F.Fab")
		)
		(fp_line
			(start -7.649972 -4.99999)
			(end -7.649972 4.99999)
			(stroke
				(width 0.1)
				(type default)
			)
			(layer "F.Fab")
		)
		(pad "D" smd circle
			(at 2.15011 0 180)
			(size 0 0)
			(layers "F.Cu" "F.Mask" "F.Paste")
			(net "P52V_HS1_DRAIN_2")
		)
		(pad "G" smd rect
			(at -7.050024 -2.54 90)
			(size 1.3208 3.0988)
			(layers "F.Cu" "F.Mask" "F.Paste")
			(net "P52V_HS1_GATE6")
		)
		(pad "S" smd rect
			(at -7.050024 2.54 90)
			(size 1.3208 3.0988)
			(layers "F.Cu" "F.Mask" "F.Paste")
			(net "P52V_HS1")
		)
		(zone
			(layer "F.Cu")
			(hatch none 0.5)
			(connect_pads
				(clearance 0)
			)
			(min_thickness 0.25)
			(keepout
				(tracks not_allowed)
				(vias allowed)
				(pads allowed)
				(copperpour not_allowed)
				(footprints allowed)
			)
			(placement
				(enabled no)
				(sheetname "")
			)
			(fill
				(thermal_gap 0.5)
				(thermal_bridge_width 0.5)
				(island_removal_mode 0)
			)
			(polygon
				(pts
					(xy 317.95466 -35.8394) (xy 330.78166 -35.8394) (xy 330.78166 -37.5666) (xy 328.57186 -37.5666)
					(xy 328.57186 -38.989) (xy 330.78166 -38.989) (xy 330.78166 -42.6466) (xy 328.57186 -42.6466) (xy 328.57186 -44.069)
					(xy 330.78166 -44.069) (xy 330.78166 -45.7962) (xy 317.95466 -45.7962) (xy 317.95466 -44.6278)
					(xy 324.15226 -44.6278) (xy 324.15226 -37.0078) (xy 317.95466 -37.0078)
				)
			)
		)
	)
	(footprint ""
		(layer "F.Cu")
		(at 172.4914 -76.835)
		(property "Reference" "R5887"
			(at 0 0 0)
			(layer "F.SilkS")
			(hide yes)
			(effects
				(font
					(size 1.27 1.27)
				)
			)
		)
		(property "Value" ""
			(at 0 0 0)
			(layer "F.Fab")
			(effects
				(font
					(size 1.27 1.27)
				)
			)
		)
		(duplicate_pad_numbers_are_jumpers no)
		(fp_line
			(start -0.7874 -0.4064)
			(end 0.7874 -0.4064)
			(stroke
				(width 0.1524)
				(type default)
			)
			(layer "F.SilkS")
		)
		(fp_line
			(start -0.7874 0.4064)
			(end -0.7874 -0.4064)
			(stroke
				(width 0.1524)
				(type default)
			)
			(layer "F.SilkS")
		)
		(fp_line
			(start 0.7874 -0.4064)
			(end 0.7874 0.4064)
			(stroke
				(width 0.1524)
				(type default)
			)
			(layer "F.SilkS")
		)
		(fp_line
			(start 0.7874 0.4064)
			(end -0.7874 0.4064)
			(stroke
				(width 0.1524)
				(type default)
			)
			(layer "F.SilkS")
		)
		(fp_line
			(start -0.67945 -0.305054)
			(end -0.12065 -0.305054)
			(stroke
				(width 0.1)
				(type default)
			)
			(layer "F.Fab")
		)
		(fp_line
			(start -0.67945 0.3048)
			(end -0.67945 -0.305054)
			(stroke
				(width 0.1)
				(type default)
			)
			(layer "F.Fab")
		)
		(fp_line
			(start -0.12065 -0.305054)
			(end -0.12065 -0.2794)
			(stroke
				(width 0.1)
				(type default)
			)
			(layer "F.Fab")
		)
		(fp_line
			(start -0.12065 -0.2794)
			(end 0.12065 -0.2794)
			(stroke
				(width 0.1)
				(type default)
			)
			(layer "F.Fab")
		)
		(fp_line
			(start -0.12065 0.2794)
			(end -0.12065 0.3048)
			(stroke
				(width 0.1)
				(type default)
			)
			(layer "F.Fab")
		)
		(fp_line
			(start -0.12065 0.3048)
			(end -0.67945 0.3048)
			(stroke
				(width 0.1)
				(type default)
			)
			(layer "F.Fab")
		)
		(fp_line
			(start 0.120396 0.2794)
			(end -0.12065 0.2794)
			(stroke
				(width 0.1)
				(type default)
			)
			(layer "F.Fab")
		)
		(fp_line
			(start 0.120396 0.3048)
			(end 0.120396 0.2794)
			(stroke
				(width 0.1)
				(type default)
			)
			(layer "F.Fab")
		)
		(fp_line
			(start 0.12065 -0.3048)
			(end 0.67945 -0.3048)
			(stroke
				(width 0.1)
				(type default)
			)
			(layer "F.Fab")
		)
		(fp_line
			(start 0.12065 -0.2794)
			(end 0.12065 -0.3048)
			(stroke
				(width 0.1)
				(type default)
			)
			(layer "F.Fab")
		)
		(fp_line
			(start 0.67945 -0.3048)
			(end 0.67945 0.3048)
			(stroke
				(width 0.1)
				(type default)
			)
			(layer "F.Fab")
		)
		(fp_line
			(start 0.67945 0.3048)
			(end 0.120396 0.3048)
			(stroke
				(width 0.1)
				(type default)
			)
			(layer "F.Fab")
		)
		(pad "1" smd circle
			(at -0.40005 0)
			(size 0 0)
			(layers "F.Cu" "F.Mask" "F.Paste")
			(net "P3V3_AUX")
		)
		(pad "2" smd circle
			(at 0.40005 0)
			(size 0 0)
			(layers "F.Cu" "F.Mask" "F.Paste")
			(net "P52V_HS2_GPO2")
		)
	)
)
